FILE_TYPE = CONNECTIVITY;
{Allegro Design Entry HDL 17.2-2016 S081 (4005846) 1/11/2022}
"PAGE_NUMBER" = 298;
0"NC";
END.
